(kicad_pcb
	(version 20241229)
	(generator "pcbnew")
	(generator_version "9.0")
	(general
		(thickness 1.6)
		(legacy_teardrops no)
	)
	(paper "A4")
	(title_block
		(title "LPDDR4 testbed")
		(date "2024-03-26")
		(rev "1.2.2")
		(comment 9 "footprints 17-23 of 66")
	)
	(layers
		(0 "F.Cu" signal)
		(4 "In1.Cu" power)
		(6 "In2.Cu" power)
		(8 "In3.Cu" signal)
		(10 "In4.Cu" signal)
		(2 "B.Cu" signal)
		(9 "F.Adhes" user "F.Adhesive")
		(11 "B.Adhes" user "B.Adhesive")
		(13 "F.Paste" user)
		(15 "B.Paste" user)
		(5 "F.SilkS" user "F.Silkscreen")
		(7 "B.SilkS" user "B.Silkscreen")
		(1 "F.Mask" user)
		(3 "B.Mask" user)
		(17 "Dwgs.User" user "User.Drawings")
		(19 "Cmts.User" user "User.Comments")
		(21 "Eco1.User" user "User.Eco1")
		(23 "Eco2.User" user "User.Eco2")
		(25 "Edge.Cuts" user)
		(27 "Margin" user)
		(31 "F.CrtYd" user "F.Courtyard")
		(29 "B.CrtYd" user "B.Courtyard")
		(35 "F.Fab" user)
		(33 "B.Fab" user)
	)
	(footprint "antmicro-footprints:R_0402_1005Metric"
		(layer "F.Cu")
		(at 158.375 88.55 180)
		(descr "Resistor SMD 0402")
		(tags "resistor SMD 0402")
		(property "Reference" "R1"
			(at -2.45 -0.35 0)
			(layer "F.SilkS")
			(effects
				(font
					(size 0.7 0.7)
					(thickness 0.15)
				)
				(justify right bottom)
			)
		)
		(property "Value" "R_10k_0402"
			(at 0 1.4 0)
			(layer "F.Fab")
			(effects
				(font
					(size 0.7 0.7)
					(thickness 0.15)
				)
				(justify right bottom)
			)
		)
		(property "Description" "10k resistor in 0402 package with 1% tolerance"
			(at 0 0 180)
			(layer "F.Fab")
			(hide yes)
			(effects
				(font
					(size 1.27 1.27)
					(thickness 0.15)
				)
			)
		)
		(property "Author" "Antmicro"
			(at 316.75 177.1 0)
			(layer "F.Fab")
			(hide yes)
			(effects
				(font
					(size 1 1)
					(thickness 0.15)
				)
			)
		)
		(property "License" "Apache-2.0"
			(at 316.75 177.1 0)
			(layer "F.Fab")
			(hide yes)
			(effects
				(font
					(size 1 1)
					(thickness 0.15)
				)
			)
		)
		(property "MPN" "CRCW040210K0FKEDHP"
			(at 316.75 177.1 0)
			(layer "F.Fab")
			(hide yes)
			(effects
				(font
					(size 1 1)
					(thickness 0.15)
				)
			)
		)
		(property "Manufacturer" "VISHAY"
			(at 316.75 177.1 0)
			(layer "F.Fab")
			(hide yes)
			(effects
				(font
					(size 1 1)
					(thickness 0.15)
				)
			)
		)
		(property "Tolerance" "1%"
			(at 316.75 177.1 0)
			(layer "F.Fab")
			(hide yes)
			(effects
				(font
					(size 1 1)
					(thickness 0.15)
				)
			)
		)
		(property "Val" "10k"
			(at 316.75 177.1 0)
			(layer "F.Fab")
			(hide yes)
			(effects
				(font
					(size 1 1)
					(thickness 0.15)
				)
			)
		)
		(sheetname "LPDDR4")
		(sheetfile "lpddr4.kicad_sch")
		(attr smd)
		(fp_rect
			(start -0.93 -0.47)
			(end 0.93 0.47)
			(stroke
				(width 0.05)
				(type solid)
			)
			(fill no)
			(layer "F.CrtYd")
		)
		(fp_rect
			(start -0.5 -0.25)
			(end 0.5 0.25)
			(stroke
				(width 0.15)
				(type solid)
			)
			(fill no)
			(layer "F.Fab")
		)
		(pad "1" smd roundrect
			(at -0.485 0 180)
			(size 0.59 0.64)
			(layers "F.Cu" "F.Mask" "F.Paste")
			(roundrect_rratio 0.25)
			(net 189 "VDDQ")
			(pintype "passive")
		)
		(pad "2" smd roundrect
			(at 0.485 0 180)
			(size 0.59 0.64)
			(layers "F.Cu" "F.Mask" "F.Paste")
			(roundrect_rratio 0.25)
			(net 158 "Net-(U1A-ODT_CA_A)")
			(pintype "passive")
		)
	)
	(footprint "antmicro-footprints:C_0201"
		(layer "F.Cu")
		(at 155.855 93.2 -90)
		(descr "Capacitor SMD 0201")
		(tags "capacitor SMD 0201")
		(property "Reference" "C1"
			(at -0.15 -1.22 90)
			(layer "F.SilkS")
			(effects
				(font
					(size 0.7 0.7)
					(thickness 0.15)
				)
				(justify right bottom)
			)
		)
		(property "Value" "C_100n_0201"
			(at 0 1.4 90)
			(layer "F.Fab")
			(effects
				(font
					(size 0.7 0.7)
					(thickness 0.15)
				)
				(justify right bottom)
			)
		)
		(property "Description" " "
			(at 0 0 270)
			(layer "F.Fab")
			(hide yes)
			(effects
				(font
					(size 1.27 1.27)
					(thickness 0.15)
				)
			)
		)
		(property "Author" "Antmicro"
			(at 62.655 249.055 0)
			(layer "F.Fab")
			(hide yes)
			(effects
				(font
					(size 1 1)
					(thickness 0.15)
				)
			)
		)
		(property "Dielectric" ""
			(at 62.655 249.055 0)
			(layer "F.Fab")
			(hide yes)
			(effects
				(font
					(size 1 1)
					(thickness 0.15)
				)
			)
		)
		(property "License" "Apache-2.0"
			(at 62.655 249.055 0)
			(layer "F.Fab")
			(hide yes)
			(effects
				(font
					(size 1 1)
					(thickness 0.15)
				)
			)
		)
		(property "MPN" "CC0201KRX6S5BB104"
			(at 62.655 249.055 0)
			(layer "F.Fab")
			(hide yes)
			(effects
				(font
					(size 1 1)
					(thickness 0.15)
				)
			)
		)
		(property "Manufacturer" "YAGEO"
			(at 62.655 249.055 0)
			(layer "F.Fab")
			(hide yes)
			(effects
				(font
					(size 1 1)
					(thickness 0.15)
				)
			)
		)
		(property "Val" "100n"
			(at 62.655 249.055 0)
			(layer "F.Fab")
			(hide yes)
			(effects
				(font
					(size 1 1)
					(thickness 0.15)
				)
			)
		)
		(property "Voltage" ""
			(at 62.655 249.055 0)
			(layer "F.Fab")
			(hide yes)
			(effects
				(font
					(size 1 1)
					(thickness 0.15)
				)
			)
		)
		(sheetname "LPDDR4")
		(sheetfile "lpddr4.kicad_sch")
		(attr smd)
		(fp_rect
			(start -0.72 -0.38)
			(end 0.72 0.38)
			(stroke
				(width 0.05)
				(type solid)
			)
			(fill no)
			(layer "F.CrtYd")
		)
		(fp_rect
			(start 0.3 0.15)
			(end -0.301 -0.149)
			(stroke
				(width 0.15)
				(type solid)
			)
			(fill no)
			(layer "F.Fab")
		)
		(pad "" smd roundrect
			(at -0.349 -0.002 270)
			(size 0.318 0.36)
			(layers "F.Paste")
			(roundrect_rratio 0.25)
		)
		(pad "" smd roundrect
			(at 0.341 -0.002 270)
			(size 0.318 0.36)
			(layers "F.Paste")
			(roundrect_rratio 0.25)
		)
		(pad "1" smd roundrect
			(at -0.321 -0.002 270)
			(size 0.46 0.4)
			(layers "F.Cu" "F.Mask")
			(roundrect_rratio 0.25)
			(net 36 "GND")
			(pintype "passive")
		)
		(pad "2" smd roundrect
			(at 0.32 -0.002 270)
			(size 0.46 0.4)
			(layers "F.Cu" "F.Mask")
			(roundrect_rratio 0.25)
			(net 189 "VDDQ")
			(pintype "passive")
		)
	)
	(footprint "antmicro-footprints:R_0402_1005Metric"
		(layer "F.Cu")
		(at 158.375 83.6 180)
		(descr "Resistor SMD 0402")
		(tags "resistor SMD 0402")
		(property "Reference" "R4"
			(at -0.8 -0.45 180)
			(layer "F.SilkS")
			(effects
				(font
					(size 0.7 0.7)
					(thickness 0.15)
				)
				(justify left bottom)
			)
		)
		(property "Value" "R_10k_0402"
			(at 0 1.4 180)
			(layer "F.Fab")
			(effects
				(font
					(size 0.7 0.7)
					(thickness 0.15)
				)
				(justify left bottom)
			)
		)
		(property "Description" "10k resistor in 0402 package with 1% tolerance"
			(at 0 0 180)
			(layer "F.Fab")
			(hide yes)
			(effects
				(font
					(size 1.27 1.27)
					(thickness 0.15)
				)
			)
		)
		(property "Author" "Antmicro"
			(at 316.75 167.2 0)
			(layer "F.Fab")
			(hide yes)
			(effects
				(font
					(size 1 1)
					(thickness 0.15)
				)
			)
		)
		(property "License" "Apache-2.0"
			(at 316.75 167.2 0)
			(layer "F.Fab")
			(hide yes)
			(effects
				(font
					(size 1 1)
					(thickness 0.15)
				)
			)
		)
		(property "MPN" "CRCW040210K0FKEDHP"
			(at 316.75 167.2 0)
			(layer "F.Fab")
			(hide yes)
			(effects
				(font
					(size 1 1)
					(thickness 0.15)
				)
			)
		)
		(property "Manufacturer" "VISHAY"
			(at 316.75 167.2 0)
			(layer "F.Fab")
			(hide yes)
			(effects
				(font
					(size 1 1)
					(thickness 0.15)
				)
			)
		)
		(property "Tolerance" "1%"
			(at 316.75 167.2 0)
			(layer "F.Fab")
			(hide yes)
			(effects
				(font
					(size 1 1)
					(thickness 0.15)
				)
			)
		)
		(property "Val" "10k"
			(at 316.75 167.2 0)
			(layer "F.Fab")
			(hide yes)
			(effects
				(font
					(size 1 1)
					(thickness 0.15)
				)
			)
		)
		(sheetname "LPDDR4")
		(sheetfile "lpddr4.kicad_sch")
		(attr smd)
		(fp_rect
			(start -0.93 -0.47)
			(end 0.93 0.47)
			(stroke
				(width 0.05)
				(type solid)
			)
			(fill no)
			(layer "F.CrtYd")
		)
		(fp_rect
			(start -0.5 -0.25)
			(end 0.5 0.25)
			(stroke
				(width 0.15)
				(type solid)
			)
			(fill no)
			(layer "F.Fab")
		)
		(pad "1" smd roundrect
			(at -0.485 0 180)
			(size 0.59 0.64)
			(layers "F.Cu" "F.Mask" "F.Paste")
			(roundrect_rratio 0.25)
			(net 189 "VDDQ")
			(pintype "passive")
		)
		(pad "2" smd roundrect
			(at 0.485 0 180)
			(size 0.59 0.64)
			(layers "F.Cu" "F.Mask" "F.Paste")
			(roundrect_rratio 0.25)
			(net 159 "Net-(U1B-ODT_CA_B)")
			(pintype "passive")
		)
	)
	(footprint "antmicro-footprints:R_0402_1005Metric"
		(layer "F.Cu")
		(at 140.725 83.95 -90)
		(descr "Resistor SMD 0402")
		(tags "resistor SMD 0402")
		(property "Reference" "R5"
			(at -0.8 0.55 90)
			(layer "F.SilkS")
			(effects
				(font
					(size 0.7 0.7)
					(thickness 0.15)
				)
				(justify right bottom)
			)
		)
		(property "Value" "R_10k_0402"
			(at 0 1.4 90)
			(layer "F.Fab")
			(effects
				(font
					(size 0.7 0.7)
					(thickness 0.15)
				)
				(justify right bottom)
			)
		)
		(property "Description" "10k resistor in 0402 package with 1% tolerance"
			(at 0 0 270)
			(layer "F.Fab")
			(hide yes)
			(effects
				(font
					(size 1.27 1.27)
					(thickness 0.15)
				)
			)
		)
		(property "Author" "Antmicro"
			(at 56.775 224.675 0)
			(layer "F.Fab")
			(hide yes)
			(effects
				(font
					(size 1 1)
					(thickness 0.15)
				)
			)
		)
		(property "License" "Apache-2.0"
			(at 56.775 224.675 0)
			(layer "F.Fab")
			(hide yes)
			(effects
				(font
					(size 1 1)
					(thickness 0.15)
				)
			)
		)
		(property "MPN" "CRCW040210K0FKEDHP"
			(at 56.775 224.675 0)
			(layer "F.Fab")
			(hide yes)
			(effects
				(font
					(size 1 1)
					(thickness 0.15)
				)
			)
		)
		(property "Manufacturer" "VISHAY"
			(at 56.775 224.675 0)
			(layer "F.Fab")
			(hide yes)
			(effects
				(font
					(size 1 1)
					(thickness 0.15)
				)
			)
		)
		(property "Tolerance" "1%"
			(at 56.775 224.675 0)
			(layer "F.Fab")
			(hide yes)
			(effects
				(font
					(size 1 1)
					(thickness 0.15)
				)
			)
		)
		(property "Val" "10k"
			(at 56.775 224.675 0)
			(layer "F.Fab")
			(hide yes)
			(effects
				(font
					(size 1 1)
					(thickness 0.15)
				)
			)
		)
		(sheetname "LPDDR4")
		(sheetfile "lpddr4.kicad_sch")
		(attr smd)
		(fp_rect
			(start -0.93 -0.47)
			(end 0.93 0.47)
			(stroke
				(width 0.05)
				(type solid)
			)
			(fill no)
			(layer "F.CrtYd")
		)
		(fp_rect
			(start -0.5 -0.25)
			(end 0.5 0.25)
			(stroke
				(width 0.15)
				(type solid)
			)
			(fill no)
			(layer "F.Fab")
		)
		(pad "1" smd roundrect
			(at -0.485 0 270)
			(size 0.59 0.64)
			(layers "F.Cu" "F.Mask" "F.Paste")
			(roundrect_rratio 0.25)
			(net 189 "VDDQ")
			(pintype "passive")
		)
		(pad "2" smd roundrect
			(at 0.485 0 270)
			(size 0.59 0.64)
			(layers "F.Cu" "F.Mask" "F.Paste")
			(roundrect_rratio 0.25)
			(net 160 "Net-(U1A-RESET_N)")
			(pintype "passive")
		)
	)
	(footprint "antmicro-footprints:R_0402_1005Metric"
		(layer "F.Cu")
		(at 141.175 85.9)
		(descr "Resistor SMD 0402")
		(tags "resistor SMD 0402")
		(property "Reference" "R7"
			(at -2.4 0.35 0)
			(layer "F.SilkS")
			(effects
				(font
					(size 0.7 0.7)
					(thickness 0.15)
				)
				(justify left bottom)
			)
		)
		(property "Value" "R_0R_0402"
			(at 0 1.4 0)
			(layer "F.Fab")
			(effects
				(font
					(size 0.7 0.7)
					(thickness 0.15)
				)
				(justify left bottom)
			)
		)
		(property "Description" "0R resistor in 0402 package with unspecified tolerance"
			(at 0 0 0)
			(layer "F.Fab")
			(hide yes)
			(effects
				(font
					(size 1.27 1.27)
					(thickness 0.15)
				)
			)
		)
		(property "Author" "Antmicro"
			(at 0 0 0)
			(layer "F.Fab")
			(hide yes)
			(effects
				(font
					(size 1 1)
					(thickness 0.15)
				)
			)
		)
		(property "Current" "1A"
			(at 0 0 0)
			(layer "F.Fab")
			(hide yes)
			(effects
				(font
					(size 1 1)
					(thickness 0.15)
				)
			)
		)
		(property "License" "Apache-2.0"
			(at 0 0 0)
			(layer "F.Fab")
			(hide yes)
			(effects
				(font
					(size 1 1)
					(thickness 0.15)
				)
			)
		)
		(property "MPN" "ERJ2GE0R00X"
			(at 0 0 0)
			(layer "F.Fab")
			(hide yes)
			(effects
				(font
					(size 1 1)
					(thickness 0.15)
				)
			)
		)
		(property "Manufacturer" "PANASONIC"
			(at 0 0 0)
			(layer "F.Fab")
			(hide yes)
			(effects
				(font
					(size 1 1)
					(thickness 0.15)
				)
			)
		)
		(property "Tolerance" ""
			(at 0 0 0)
			(layer "F.Fab")
			(hide yes)
			(effects
				(font
					(size 1 1)
					(thickness 0.15)
				)
			)
		)
		(property "Val" "0R"
			(at 0 0 0)
			(layer "F.Fab")
			(hide yes)
			(effects
				(font
					(size 1 1)
					(thickness 0.15)
				)
			)
		)
		(sheetname "LPDDR4")
		(sheetfile "lpddr4.kicad_sch")
		(attr smd)
		(fp_rect
			(start -0.93 -0.47)
			(end 0.93 0.47)
			(stroke
				(width 0.05)
				(type solid)
			)
			(fill no)
			(layer "F.CrtYd")
		)
		(fp_rect
			(start -0.5 -0.25)
			(end 0.5 0.25)
			(stroke
				(width 0.15)
				(type solid)
			)
			(fill no)
			(layer "F.Fab")
		)
		(pad "1" smd roundrect
			(at -0.485 0)
			(size 0.59 0.64)
			(layers "F.Cu" "F.Mask" "F.Paste")
			(roundrect_rratio 0.25)
			(net 160 "Net-(U1A-RESET_N)")
			(pintype "passive")
		)
		(pad "2" smd roundrect
			(at 0.485 0)
			(size 0.59 0.64)
			(layers "F.Cu" "F.Mask" "F.Paste")
			(roundrect_rratio 0.25)
			(net 230 "RESET_N")
			(pintype "passive")
		)
	)
	(footprint "antmicro-footprints:R_0402_1005Metric"
		(layer "F.Cu")
		(at 150.416 94.969)
		(descr "Resistor SMD 0402")
		(tags "resistor SMD 0402")
		(property "Reference" "R6"
			(at -1.041 -0.519 0)
			(layer "F.SilkS")
			(effects
				(font
					(size 0.7 0.7)
					(thickness 0.15)
				)
				(justify left bottom)
			)
		)
		(property "Value" "R_240R_0402"
			(at 0 1.4 0)
			(layer "F.Fab")
			(effects
				(font
					(size 0.7 0.7)
					(thickness 0.15)
				)
				(justify left bottom)
			)
		)
		(property "Description" "240R resistor in 0402 package with 1% tolerance"
			(at 0 0 0)
			(layer "F.Fab")
			(hide yes)
			(effects
				(font
					(size 1.27 1.27)
					(thickness 0.15)
				)
			)
		)
		(property "Author" "Antmicro"
			(at 0 0 0)
			(layer "F.Fab")
			(hide yes)
			(effects
				(font
					(size 1 1)
					(thickness 0.15)
				)
			)
		)
		(property "License" "Apache-2.0"
			(at 0 0 0)
			(layer "F.Fab")
			(hide yes)
			(effects
				(font
					(size 1 1)
					(thickness 0.15)
				)
			)
		)
		(property "MPN" "ERJ2GEJ241X"
			(at 0 0 0)
			(layer "F.Fab")
			(hide yes)
			(effects
				(font
					(size 1 1)
					(thickness 0.15)
				)
			)
		)
		(property "Manufacturer" "PANASONIC"
			(at 0 0 0)
			(layer "F.Fab")
			(hide yes)
			(effects
				(font
					(size 1 1)
					(thickness 0.15)
				)
			)
		)
		(property "Tolerance" "1%"
			(at 0 0 0)
			(layer "F.Fab")
			(hide yes)
			(effects
				(font
					(size 1 1)
					(thickness 0.15)
				)
			)
		)
		(property "Val" "240R"
			(at 0 0 0)
			(layer "F.Fab")
			(hide yes)
			(effects
				(font
					(size 1 1)
					(thickness 0.15)
				)
			)
		)
		(sheetname "LPDDR4")
		(sheetfile "lpddr4.kicad_sch")
		(attr smd)
		(fp_rect
			(start -0.93 -0.47)
			(end 0.93 0.47)
			(stroke
				(width 0.05)
				(type solid)
			)
			(fill no)
			(layer "F.CrtYd")
		)
		(fp_rect
			(start -0.5 -0.25)
			(end 0.5 0.25)
			(stroke
				(width 0.15)
				(type solid)
			)
			(fill no)
			(layer "F.Fab")
		)
		(pad "1" smd roundrect
			(at -0.485 0)
			(size 0.59 0.64)
			(layers "F.Cu" "F.Mask" "F.Paste")
			(roundrect_rratio 0.25)
			(net 161 "Net-(U1A-ZQ0)")
			(pintype "passive")
		)
		(pad "2" smd roundrect
			(at 0.485 0)
			(size 0.59 0.64)
			(layers "F.Cu" "F.Mask" "F.Paste")
			(roundrect_rratio 0.25)
			(net 36 "GND")
			(pintype "passive")
		)
	)
	(footprint "antmicro-footprints:C_0201"
		(layer "F.Cu")
		(at 142.925 82.75 90)
		(descr "Capacitor SMD 0201")
		(tags "capacitor SMD 0201")
		(property "Reference" "C24"
			(at -0.6 -0.55 90)
			(layer "F.SilkS")
			(effects
				(font
					(size 0.7 0.7)
					(thickness 0.15)
				)
				(justify left bottom)
			)
		)
		(property "Value" "C_100n_0201"
			(at 0 1.4 90)
			(layer "F.Fab")
			(effects
				(font
					(size 0.7 0.7)
					(thickness 0.15)
				)
				(justify left bottom)
			)
		)
		(property "Description" " "
			(at 0 0 90)
			(layer "F.Fab")
			(hide yes)
			(effects
				(font
					(size 1.27 1.27)
					(thickness 0.15)
				)
			)
		)
		(property "Author" "Antmicro"
			(at 225.675 -60.175 0)
			(layer "F.Fab")
			(hide yes)
			(effects
				(font
					(size 1 1)
					(thickness 0.15)
				)
			)
		)
		(property "Dielectric" ""
			(at 225.675 -60.175 0)
			(layer "F.Fab")
			(hide yes)
			(effects
				(font
					(size 1 1)
					(thickness 0.15)
				)
			)
		)
		(property "License" "Apache-2.0"
			(at 225.675 -60.175 0)
			(layer "F.Fab")
			(hide yes)
			(effects
				(font
					(size 1 1)
					(thickness 0.15)
				)
			)
		)
		(property "MPN" "CC0201KRX6S5BB104"
			(at 225.675 -60.175 0)
			(layer "F.Fab")
			(hide yes)
			(effects
				(font
					(size 1 1)
					(thickness 0.15)
				)
			)
		)
		(property "Manufacturer" "YAGEO"
			(at 225.675 -60.175 0)
			(layer "F.Fab")
			(hide yes)
			(effects
				(font
					(size 1 1)
					(thickness 0.15)
				)
			)
		)
		(property "Val" "100n"
			(at 225.675 -60.175 0)
			(layer "F.Fab")
			(hide yes)
			(effects
				(font
					(size 1 1)
					(thickness 0.15)
				)
			)
		)
		(property "Voltage" ""
			(at 225.675 -60.175 0)
			(layer "F.Fab")
			(hide yes)
			(effects
				(font
					(size 1 1)
					(thickness 0.15)
				)
			)
		)
		(sheetname "LPDDR4")
		(sheetfile "lpddr4.kicad_sch")
		(attr smd)
		(fp_rect
			(start -0.72 -0.38)
			(end 0.72 0.38)
			(stroke
				(width 0.05)
				(type solid)
			)
			(fill no)
			(layer "F.CrtYd")
		)
		(fp_rect
			(start 0.3 0.15)
			(end -0.301 -0.149)
			(stroke
				(width 0.15)
				(type solid)
			)
			(fill no)
			(layer "F.Fab")
		)
		(pad "" smd roundrect
			(at -0.349 -0.002 90)
			(size 0.318 0.36)
			(layers "F.Paste")
			(roundrect_rratio 0.25)
		)
		(pad "" smd roundrect
			(at 0.341 -0.002 90)
			(size 0.318 0.36)
			(layers "F.Paste")
			(roundrect_rratio 0.25)
		)
		(pad "1" smd roundrect
			(at -0.321 -0.002 90)
			(size 0.46 0.4)
			(layers "F.Cu" "F.Mask")
			(roundrect_rratio 0.25)
			(net 36 "GND")
			(pintype "passive")
		)
		(pad "2" smd roundrect
			(at 0.32 -0.002 90)
			(size 0.46 0.4)
			(layers "F.Cu" "F.Mask")
			(roundrect_rratio 0.25)
			(net 187 "VDD1")
			(pintype "passive")
		)
	)
)
